# T6G (Grand Teton) — schematic netlist excerpt (pin names and nets, part order shuffled) for the footprints in the layout excerpt that follows; sources: Cadence DE-HDL packaged netlist, KiCad conversion of 04192023_DAF0TMB3IC0_F0TG_MB_C_brd_V02_OCP.brd

X8028  TP_TDR_4P_FTS  TP_TDR_4P_DIP EMPTY  pkg TH  page 260
  S1  = TDR_DIFF_85_IN6_DN
  P1  = T1_GND
  P2  = T1_GND
  S2  = TDR_DIFF_85_IN6_DP

C5236  Q_CAP  0.1UF 25V 10% EMPTY  pkg C0402  page 234 : A = PD_U5201_VREG ; B = GND

(kicad_pcb
	(version 20260206)
	(generator "pcbnew")
	(generator_version "10.0")
	(general
		(thickness 1.6)
		(legacy_teardrops no)
	)
	(paper "A4")
	(title_block
		(title "04192023_DAF0TMB3IC0_F0TG_MB_C_brd_V02_OCP.brd")
		(comment 1 "Grand Teton / footprints 7935-7936 of 8354")
	)
	(layers
		(0 "F.Cu" signal "TOP")
		(4 "In1.Cu" signal "GND")
		(6 "In2.Cu" signal "IN1")
		(8 "In3.Cu" signal "GND1")
		(10 "In4.Cu" signal "IN2")
		(12 "In5.Cu" signal "GND2")
		(14 "In6.Cu" signal "IN3")
		(16 "In7.Cu" signal "GND3")
		(18 "In8.Cu" signal "VCC")
		(20 "In9.Cu" signal "VCC1")
		(22 "In10.Cu" signal "GND4")
		(24 "In11.Cu" signal "IN4")
		(26 "In12.Cu" signal "GND5")
		(28 "In13.Cu" signal "IN5")
		(30 "In14.Cu" signal "GND6")
		(32 "In15.Cu" signal "IN6")
		(34 "In16.Cu" signal "GND7")
		(2 "B.Cu" signal "BOTTOM")
		(9 "F.Adhes" user "F.Adhesive")
		(11 "B.Adhes" user "B.Adhesive")
		(13 "F.Paste" user "Package Geometry/Pastemask Top")
		(15 "B.Paste" user "Package Geometry/Pastemask Bottom")
		(5 "F.SilkS" user "Ref Des/Silkscreen Top")
		(7 "B.SilkS" user "Ref Des/Silkscreen Bottom")
		(1 "F.Mask" user "Board Geometry/Soldermask Top")
		(3 "B.Mask" user "Board Geometry/Soldermask Bottom")
		(17 "Dwgs.User" user "User.Drawings")
		(19 "Cmts.User" user "User.Comments")
		(21 "Eco1.User" user "User.Eco1")
		(23 "Eco2.User" user "User.Eco2")
		(25 "Edge.Cuts" user "Board Geometry/Outline")
		(27 "Margin" user)
		(31 "F.CrtYd" user "Package Geometry/Place Bound Top")
		(29 "B.CrtYd" user "Package Geometry/Place Bound Bottom")
		(35 "F.Fab" user "Ref Des/Assembly Top")
		(33 "B.Fab" user "Ref Des/Assembly Bottom")
	)
	(footprint ""
		(layer "B.Cu")
		(at 16.237712 -112.693958 180)
		(property "Reference" "C5236"
			(at 0 0 0)
			(layer "B.SilkS")
			(hide yes)
			(effects
				(font
					(size 1.27 1.27)
				)
				(justify mirror)
			)
		)
		(property "Value" ""
			(at 0 0 0)
			(layer "B.Fab")
			(effects
				(font
					(size 1.27 1.27)
				)
				(justify mirror)
			)
		)
		(duplicate_pad_numbers_are_jumpers no)
		(fp_line
			(start 0.7874 0.4064)
			(end 0.7874 -0.4064)
			(stroke
				(width 0.1524)
				(type default)
			)
			(layer "B.SilkS")
		)
		(fp_line
			(start 0.7874 -0.4064)
			(end -0.7874 -0.4064)
			(stroke
				(width 0.1524)
				(type default)
			)
			(layer "B.SilkS")
		)
		(fp_line
			(start -0.7874 0.4064)
			(end 0.7874 0.4064)
			(stroke
				(width 0.1524)
				(type default)
			)
			(layer "B.SilkS")
		)
		(fp_line
			(start -0.7874 -0.4064)
			(end -0.7874 0.4064)
			(stroke
				(width 0.1524)
				(type default)
			)
			(layer "B.SilkS")
		)
		(fp_line
			(start 0.67945 0.3048)
			(end 0.67945 -0.305054)
			(stroke
				(width 0.1)
				(type default)
			)
			(layer "B.Fab")
		)
		(fp_line
			(start 0.67945 -0.305054)
			(end 0.12065 -0.305054)
			(stroke
				(width 0.1)
				(type default)
			)
			(layer "B.Fab")
		)
		(fp_line
			(start 0.12065 0.3048)
			(end 0.67945 0.3048)
			(stroke
				(width 0.1)
				(type default)
			)
			(layer "B.Fab")
		)
		(fp_line
			(start 0.12065 0.2794)
			(end 0.12065 0.3048)
			(stroke
				(width 0.1)
				(type default)
			)
			(layer "B.Fab")
		)
		(fp_line
			(start 0.12065 -0.2794)
			(end -0.12065 -0.2794)
			(stroke
				(width 0.1)
				(type default)
			)
			(layer "B.Fab")
		)
		(fp_line
			(start 0.12065 -0.305054)
			(end 0.12065 -0.2794)
			(stroke
				(width 0.1)
				(type default)
			)
			(layer "B.Fab")
		)
		(fp_line
			(start -0.120396 0.3048)
			(end -0.120396 0.2794)
			(stroke
				(width 0.1)
				(type default)
			)
			(layer "B.Fab")
		)
		(fp_line
			(start -0.120396 0.2794)
			(end 0.12065 0.2794)
			(stroke
				(width 0.1)
				(type default)
			)
			(layer "B.Fab")
		)
		(fp_line
			(start -0.12065 -0.2794)
			(end -0.12065 -0.3048)
			(stroke
				(width 0.1)
				(type default)
			)
			(layer "B.Fab")
		)
		(fp_line
			(start -0.12065 -0.3048)
			(end -0.67945 -0.3048)
			(stroke
				(width 0.1)
				(type default)
			)
			(layer "B.Fab")
		)
		(fp_line
			(start -0.67945 0.3048)
			(end -0.120396 0.3048)
			(stroke
				(width 0.1)
				(type default)
			)
			(layer "B.Fab")
		)
		(fp_line
			(start -0.67945 -0.3048)
			(end -0.67945 0.3048)
			(stroke
				(width 0.1)
				(type default)
			)
			(layer "B.Fab")
		)
		(pad "1" smd circle
			(at 0.40005 0)
			(size 0 0)
			(layers "B.Cu" "B.Mask" "B.Paste")
			(net "PD_U5201_VREG")
		)
		(pad "2" smd circle
			(at -0.40005 0)
			(size 0 0)
			(layers "B.Cu" "B.Mask" "B.Paste")
			(net "GND")
		)
	)
	(footprint ""
		(layer "B.Cu")
		(at 495.90833 -142.853918 -90)
		(property "Reference" "X8028"
			(at 4.4577 -1.50495 270)
			(unlocked yes)
			(layer "B.SilkS")
			(effects
				(font
					(size 0.7874 0.5842)
					(thickness 0.1524)
				)
				(justify left mirror)
			)
		)
		(property "Value" ""
			(at 0 0 90)
			(layer "B.Fab")
			(effects
				(font
					(size 1.27 1.27)
				)
				(justify mirror)
			)
		)
		(property "Device Type" "TP_TDR_4P_FTS_TH-TP_TDR_4P_DIP,EMPTY,TP15"
			(at -1.30175 1.27 180)
			(unlocked yes)
			(layer "B.Fab")
			(hide yes)
			(effects
				(font
					(size 0.635 0.4064)
					(thickness 0.1524)
				)
				(justify mirror)
			)
		)
		(property "User Part Number" "N_A"
			(at -1.30175 1.27 180)
			(unlocked yes)
			(layer "Cmts.User")
			(hide yes)
			(effects
				(font
					(size 0.635 0.4064)
					(thickness 0.1524)
				)
				(justify mirror)
			)
		)
		(duplicate_pad_numbers_are_jumpers no)
		(fp_line
			(start -2.54 3.81)
			(end -2.54 3.6703)
			(stroke
				(width 0.1524)
				(type default)
			)
			(layer "B.SilkS")
		)
		(fp_line
			(start 0 3.81)
			(end -2.54 3.81)
			(stroke
				(width 0.1524)
				(type default)
			)
			(layer "B.SilkS")
		)
		(fp_line
			(start 0 3.175)
			(end 0 3.81)
			(stroke
				(width 0.1524)
				(type default)
			)
			(layer "B.SilkS")
		)
		(fp_line
			(start -2.54 1.4097)
			(end -2.54 1.1303)
			(stroke
				(width 0.1524)
				(type default)
			)
			(layer "B.SilkS")
		)
		(fp_line
			(start 0 0.635)
			(end 0 1.905)
			(stroke
				(width 0.1524)
				(type default)
			)
			(layer "B.SilkS")
		)
		(fp_line
			(start -2.54 -1.1303)
			(end -2.54 -1.27)
			(stroke
				(width 0.1524)
				(type default)
			)
			(layer "B.SilkS")
		)
		(fp_line
			(start -2.54 -1.27)
			(end 0 -1.27)
			(stroke
				(width 0.1524)
				(type default)
			)
			(layer "B.SilkS")
		)
		(fp_line
			(start 0 -1.27)
			(end 0 -0.635)
			(stroke
				(width 0.1524)
				(type default)
			)
			(layer "B.SilkS")
		)
		(fp_poly
			(pts
				(xy 0.761746 0) (xy 2.285746 -0.762) (xy 2.285746 0.762)
			)
			(stroke
				(width 0)
				(type default)
			)
			(fill yes)
			(layer "B.SilkS")
		)
		(fp_line
			(start -2.54 3.81)
			(end -2.54 -1.27)
			(stroke
				(width 0.1)
				(type default)
			)
			(layer "B.Fab")
		)
		(fp_line
			(start 0 3.81)
			(end -2.54 3.81)
			(stroke
				(width 0.1)
				(type default)
			)
			(layer "B.Fab")
		)
		(fp_line
			(start -2.54 -1.27)
			(end 0 -1.27)
			(stroke
				(width 0.1)
				(type default)
			)
			(layer "B.Fab")
		)
		(fp_line
			(start 0 -1.27)
			(end 0 3.81)
			(stroke
				(width 0.1)
				(type default)
			)
			(layer "B.Fab")
		)
		(fp_poly
			(pts
				(xy 0.761746 0) (xy 2.285746 -0.762) (xy 2.285746 0.762)
			)
			(stroke
				(width 0)
				(type default)
			)
			(fill yes)
			(layer "B.Fab")
		)
		(pad "1" thru_hole circle
			(at 0 0 90)
			(size 1.0033 1.0033)
			(drill 0.249936)
			(layers "*.Cu" "*.Mask")
			(remove_unused_layers no)
			(net "TDR_DIFF_85_IN6_DN")
			(clearance 0.10795)
			(padstack
				(mode front_inner_back)
				(layer "Inner"
					(shape circle)
					(size 0.8001 0.8001)
					(clearance 0.1524)
				)
				(layer "B.Cu"
					(shape circle)
					(size 1.0033 1.0033)
					(thermal_gap 0.10795)
					(clearance 0.10795)
				)
			)
		)
		(pad "2" thru_hole circle
			(at -2.54 0 90)
			(size 1.9939 1.9939)
			(drill 0.249936)
			(layers "*.Cu" "*.Mask")
			(remove_unused_layers no)
			(net "T1_GND")
			(clearance 0.10795)
			(padstack
				(mode front_inner_back)
				(layer "Inner"
					(shape circle)
					(size 0.8001 0.8001)
					(clearance 0.1524)
				)
				(layer "B.Cu"
					(shape circle)
					(size 1.9939 1.9939)
					(thermal_gap 0.10795)
					(clearance 0.10795)
				)
			)
		)
		(pad "3" thru_hole circle
			(at -2.54 2.54 90)
			(size 1.9939 1.9939)
			(drill 0.249936)
			(layers "*.Cu" "*.Mask")
			(remove_unused_layers no)
			(net "T1_GND")
			(clearance 0.10795)
			(padstack
				(mode front_inner_back)
				(layer "Inner"
					(shape circle)
					(size 0.8001 0.8001)
					(clearance 0.1524)
				)
				(layer "B.Cu"
					(shape circle)
					(size 1.9939 1.9939)
					(thermal_gap 0.10795)
					(clearance 0.10795)
				)
			)
		)
		(pad "4" thru_hole circle
			(at 0 2.54 90)
			(size 1.0033 1.0033)
			(drill 0.249936)
			(layers "*.Cu" "*.Mask")
			(remove_unused_layers no)
			(net "TDR_DIFF_85_IN6_DP")
			(clearance 0.10795)
			(padstack
				(mode front_inner_back)
				(layer "Inner"
					(shape circle)
					(size 0.8001 0.8001)
					(clearance 0.1524)
				)
				(layer "B.Cu"
					(shape circle)
					(size 1.0033 1.0033)
					(thermal_gap 0.10795)
					(clearance 0.10795)
				)
			)
		)
	)
)
